(kicad_pcb
	(version 20221018)
	(generator pcbnew)
	(general
    (thickness 1.562)
  )
	(paper "A4")
	(title_block
    (title "Thunderbolt PCIe Adaper")
    (date "2024-07-09")
    (rev "1.0.3")
    (comment 1 "www.antmicro.com")
    (comment 2 "Antmicro Ltd.")
		(comment 9 "footprints 1-9 of 271")
	)
	(layers
    (0 "F.Cu" signal)
    (1 "In1.Cu" signal)
    (2 "In2.Cu" signal)
    (3 "In3.Cu" signal)
    (4 "In4.Cu" signal)
    (31 "B.Cu" signal)
    (32 "B.Adhes" user "B.Adhesive")
    (33 "F.Adhes" user "F.Adhesive")
    (34 "B.Paste" user)
    (35 "F.Paste" user)
    (36 "B.SilkS" user "B.Silkscreen")
    (37 "F.SilkS" user "F.Silkscreen")
    (38 "B.Mask" user)
    (39 "F.Mask" user)
    (40 "Dwgs.User" user "User.Drawings")
    (41 "Cmts.User" user "User.Comments")
    (42 "Eco1.User" user "User.Eco1")
    (43 "Eco2.User" user "User.Eco2")
    (44 "Edge.Cuts" user)
    (45 "Margin" user)
    (46 "B.CrtYd" user "B.Courtyard")
    (47 "F.CrtYd" user "F.Courtyard")
    (48 "B.Fab" user)
    (49 "F.Fab" user)
  )
	(footprint "antmicro-footprints:TP_SMD_1mm" (layer "F.Cu")
    (at 110.211001 60.488 90)
    (property "Author" "Antmicro")
    (property "License" "Apache-2.0")
    (property "MPN" "")
    (property "Manufacturer" "")
    (property "Sheetfile" "power.kicad_sch")
    (property "Sheetname" "Power")
    (property "exclude_from_bom" "")
    (property "ki_description" "Test point 1mm SMD")
    (property "ki_keywords" "TESTPOINT")
    (attr exclude_from_pos_files exclude_from_bom)
    (fp_text reference "TP2" (at 0.798 -0.991001 180) (layer "F.SilkS")
        (effects (font (size 0.7 0.7) (thickness 0.15)) (justify left bottom))
    )
    (fp_text value "TP_1mm_SMD" (at 0 1.4 90) (layer "F.Fab")
        (effects (font (size 0.7 0.7) (thickness 0.15)) (justify left bottom))
    )
    (fp_text user "${REFERENCE}" (at -0.5 2.8 90) (layer "F.Fab") hide
        (effects (font (size 0.7 0.7) (thickness 0.15)) (justify left bottom))
    )
    (fp_text user "License: Apache-2.0" (at -0.5 5.2 90) (layer "F.Fab") hide
        (effects (font (size 0.7 0.7) (thickness 0.15)) (justify left bottom))
    )
    (fp_text user "Author: Antmicro" (at -0.5 4 90) (layer "F.Fab") hide
        (effects (font (size 0.7 0.7) (thickness 0.15)) (justify left bottom))
    )
    (fp_circle (center 0 0) (end 0.6 0)
      (stroke (width 0.05) (type default)) (fill none) (layer "F.CrtYd"))
    (pad "1" smd circle (at 0 0 90) (size 1 1) (layers "F.Cu" "F.Mask")
      (net 90 "Net-(U2-VIN)") (pinfunction "1") (pintype "passive"))
  )
	(footprint "antmicro-footprints:LED_0603_1608Metric_G" (layer "F.Cu")
    (at 126.25 62.75 180)
    (descr "LED SMD 0603 Green")
    (tags "LED SMD 0603 Green")
    (property "Author" "Antmicro")
    (property "Color" "Green")
    (property "License" "Apache-2.0")
    (property "MPN" "KP-1608CGCK")
    (property "Manufacturer" "Kingbright")
    (property "Sheetfile" "power.kicad_sch")
    (property "Sheetname" "Power")
    (property "ki_description" "LED, Green, SMD, 0603, 20 mA, 2.1 V, 570 nm")
    (property "ki_keywords" "SMT, DIODE, SEMICONDUCTOR, LED")
    (attr smd)
    (fp_text reference "D2" (at 0.647 -1.639 180) (layer "F.SilkS")
        (effects (font (size 0.7 0.7) (thickness 0.15)) (justify left bottom))
    )
    (fp_text value "LED_G_0603_KP-1608CGCK" (at -0.001 1.599 180) (layer "F.Fab")
        (effects (font (size 0.7 0.7) (thickness 0.15)) (justify left bottom))
    )
    (fp_text user "License: Apache-2.0" (at -1.4224 3.599 180) (layer "F.Fab") hide
        (effects (font (size 0.7 0.7) (thickness 0.15)) (justify left bottom))
    )
    (fp_text user "Author: Antmicro" (at -1.4224 4.799 180) (layer "F.Fab") hide
        (effects (font (size 0.7 0.7) (thickness 0.15)) (justify left bottom))
    )
    (fp_text user "${REFERENCE}" (at -1.4224 5.999 180) (layer "F.Fab") hide
        (effects (font (size 0.7 0.7) (thickness 0.15)) (justify left bottom))
    )
    (fp_line (start -1.18 -0.319) (end -1.18 0.321)
      (stroke (width 0.15) (type solid)) (layer "F.SilkS"))
    (fp_line (start -0.094672 0.001008) (end -0.24 0.001008)
      (stroke (width 0.1) (type solid)) (layer "F.SilkS"))
    (fp_line (start -0.094672 0.001008) (end 0.105328 -0.198992)
      (stroke (width 0.1) (type solid)) (layer "F.SilkS"))
    (fp_line (start -0.094672 0.201008) (end -0.094672 -0.198992)
      (stroke (width 0.1) (type solid)) (layer "F.SilkS"))
    (fp_line (start 0.105328 0.001008) (end 0.24 0.001)
      (stroke (width 0.1) (type solid)) (layer "F.SilkS"))
    (fp_line (start 0.105328 0.201008) (end -0.094672 0.001008)
      (stroke (width 0.1) (type solid)) (layer "F.SilkS"))
    (fp_line (start 0.105328 0.201008) (end 0.105328 -0.198992)
      (stroke (width 0.1) (type solid)) (layer "F.SilkS"))
    (fp_line (start 0.22 -0.35) (end -0.22 -0.35)
      (stroke (width 0.15) (type solid)) (layer "F.SilkS"))
    (fp_line (start 0.22 0.35) (end -0.22 0.35)
      (stroke (width 0.15) (type solid)) (layer "F.SilkS"))
    (fp_rect (start 1.25 0.65) (end -1.25 -0.65)
      (stroke (width 0.05) (type solid)) (fill none) (layer "F.CrtYd"))
    (fp_line (start -0.199 -0.202) (end -0.199 0.1)
      (stroke (width 0.15) (type solid)) (layer "F.Fab"))
    (fp_line (start -0.199 0) (end -0.597 0)
      (stroke (width 0.15) (type solid)) (layer "F.Fab"))
    (fp_line (start -0.199 0.2) (end -0.199 0.1)
      (stroke (width 0.15) (type solid)) (layer "F.Fab"))
    (fp_line (start -0.101 0) (end 0.201 0.2)
      (stroke (width 0.15) (type solid)) (layer "F.Fab"))
    (fp_line (start 0.201 -0.202) (end -0.101 0)
      (stroke (width 0.15) (type solid)) (layer "F.Fab"))
    (fp_line (start 0.201 0) (end 0.201 -0.202)
      (stroke (width 0.15) (type solid)) (layer "F.Fab"))
    (fp_line (start 0.201 0.2) (end 0.201 0)
      (stroke (width 0.15) (type solid)) (layer "F.Fab"))
    (fp_line (start 0.599 0) (end 0.201 0)
      (stroke (width 0.15) (type solid)) (layer "F.Fab"))
    (fp_rect (start 0.848 0.4) (end -0.85 -0.402)
      (stroke (width 0.15) (type solid)) (fill none) (layer "F.Fab"))
    (pad "1" smd roundrect (at -0.7 0) (size 0.8 1) (layers "F.Cu" "F.Paste" "F.Mask") (roundrect_rratio 0.2)
      (net 120 "Net-(D2-C)") (pinfunction "C") (pintype "passive"))
    (pad "2" smd roundrect (at 0.7 0) (size 0.8 1) (layers "F.Cu" "F.Paste" "F.Mask") (roundrect_rratio 0.2)
      (net 100 "Net-(D2-A)") (pinfunction "A") (pintype "passive"))
  )
	(footprint "antmicro-footprints:C_1206_3216Metric" (layer "F.Cu")
    (at 103.265 82.86 90)
    (descr "Capacitor SMD 1206")
    (tags "capacitor SMD 1206")
    (property "Author" "Antmicro")
    (property "Dielectric" "")
    (property "License" "Apache-2.0")
    (property "MPN" "3216X5R1V226M160AC")
    (property "Manufacturer" "TDK")
    (property "Sheetfile" "power.kicad_sch")
    (property "Sheetname" "Power")
    (property "Val" "22u")
    (property "Voltage" "35V")
    (property "ki_description" "SMD Multilayer Ceramic Capacitors, 22µF, 35V, X5R, 1206 [2316 Metric], 20% ")
    (property "ki_keywords" "1206, SMT, CAPACITOR, PASSIVE, CERAMIC, MLCC")
    (attr smd)
    (fp_text reference "C10" (at -0.96 -1.411 90) (layer "F.SilkS")
        (effects (font (size 0.7 0.7) (thickness 0.15)) (justify left bottom))
    )
    (fp_text value "C_22u_1206_35V" (at 0 2.101 90) (layer "F.Fab")
        (effects (font (size 0.7 0.7) (thickness 0.15)) (justify left bottom))
    )
    (fp_text user "${REFERENCE}" (at -2.625 4.101 90) (layer "F.Fab") hide
        (effects (font (size 0.7 0.7) (thickness 0.15)) (justify left bottom))
    )
    (fp_text user "Author: Antmicro" (at -2.625 5.301 90) (layer "F.Fab") hide
        (effects (font (size 0.7 0.7) (thickness 0.15)) (justify left bottom))
    )
    (fp_text user "License: Apache-2.0" (at -2.625 6.501 90) (layer "F.Fab") hide
        (effects (font (size 0.7 0.7) (thickness 0.15)) (justify left bottom))
    )
    (fp_line (start 0.8 -0.899) (end -0.8 -0.899)
      (stroke (width 0.15) (type solid)) (layer "F.SilkS"))
    (fp_line (start 0.8 0.901) (end -0.8 0.901)
      (stroke (width 0.15) (type solid)) (layer "F.SilkS"))
    (fp_rect (start -2.325 -1.15) (end 2.325 1.15)
      (stroke (width 0.05) (type default)) (fill none) (layer "F.CrtYd"))
    (fp_rect (start -1.6 -0.799) (end 1.6 0.801)
      (stroke (width 0.15) (type solid)) (fill none) (layer "F.Fab"))
    (pad "1" smd roundrect (at -1.5 0.001 90) (size 1.15 1.8) (layers "F.Cu" "F.Paste" "F.Mask") (roundrect_rratio 0.25)
      (net 1 "GND") (pintype "passive"))
    (pad "2" smd roundrect (at 1.5 0.001 90) (size 1.15 1.8) (layers "F.Cu" "F.Paste" "F.Mask") (roundrect_rratio 0.25)
      (net 74 "Net-(C10-Pad2)") (pintype "passive"))
  )
	(footprint "antmicro-footprints:D_SOD-323F" (layer "F.Cu")
    (at 116.3 62.23)
    (property "Author" "Antmicro")
    (property "License" "Apache-2.0")
    (property "MPN" "MM3Z3V3C")
    (property "Manufacturer" "ON Semiconductor")
    (property "Sheetfile" "power.kicad_sch")
    (property "Sheetname" "Power")
    (property "ki_description" "Zener Single Diode, 3.3 V, 200 mW, SOD-323F, 2 Pins, 150 °C, Surface Mount")
    (property "ki_keywords" "SMT, DIODE, SEMICONDUCTOR, ZENER")
    (attr smd)
    (fp_text reference "D1" (at -4.413 -1.016) (layer "F.SilkS")
        (effects (font (size 0.7 0.7) (thickness 0.15)) (justify left bottom))
    )
    (fp_text value "MM3Z3V3C" (at 0 1.9) (layer "F.Fab")
        (effects (font (size 0.7 0.7) (thickness 0.15)) (justify left bottom))
    )
    (fp_text user "${REFERENCE}" (at -1.7 5.099) (layer "F.Fab") hide
        (effects (font (size 0.7 0.7) (thickness 0.15)) (justify left bottom))
    )
    (fp_text user "License: Apache-2.0" (at -1.7 6.299) (layer "F.Fab") hide
        (effects (font (size 0.7 0.7) (thickness 0.15)) (justify left bottom))
    )
    (fp_text user "Author: Antmicro" (at -1.7 3.899) (layer "F.Fab") hide
        (effects (font (size 0.7 0.7) (thickness 0.15)) (justify left bottom))
    )
    (fp_line (start -0.975 -0.749) (end -0.975 -0.449)
      (stroke (width 0.15) (type solid)) (layer "F.SilkS"))
    (fp_line (start -0.975 0.749) (end -0.975 0.451)
      (stroke (width 0.15) (type solid)) (layer "F.SilkS"))
    (fp_line (start -0.625 -0.749) (end -0.975 -0.749)
      (stroke (width 0.15) (type solid)) (layer "F.SilkS"))
    (fp_line (start -0.625 0.749) (end -0.975 0.749)
      (stroke (width 0.15) (type solid)) (layer "F.SilkS"))
    (fp_line (start -0.5 -0.425) (end -0.5 0.425)
      (stroke (width 0.15) (type solid)) (layer "F.SilkS"))
    (fp_line (start 0.623 -0.749) (end 0.973 -0.749)
      (stroke (width 0.15) (type solid)) (layer "F.SilkS"))
    (fp_line (start 0.973 -0.749) (end 0.973 -0.449)
      (stroke (width 0.15) (type solid)) (layer "F.SilkS"))
    (fp_line (start 0.973 0.451) (end 0.973 0.749)
      (stroke (width 0.15) (type solid)) (layer "F.SilkS"))
    (fp_line (start 0.973 0.749) (end 0.623 0.749)
      (stroke (width 0.15) (type solid)) (layer "F.SilkS"))
    (fp_rect (start -1.55 -0.95) (end 1.55 0.95)
      (stroke (width 0.05) (type solid)) (fill none) (layer "F.CrtYd"))
    (fp_rect (start -1.25 -0.676) (end 1.245365 0.676)
      (stroke (width 0.1) (type solid)) (fill none) (layer "F.Fab"))
    (pad "1" smd roundrect (at -1.051 0.001) (size 0.8 0.6) (layers "F.Cu" "F.Paste" "F.Mask") (roundrect_rratio 0.15)
      (net 119 "Net-(D1-C)") (pinfunction "C") (pintype "passive"))
    (pad "2" smd roundrect (at 1.05 0.001) (size 0.8 0.6) (layers "F.Cu" "F.Paste" "F.Mask") (roundrect_rratio 0.15)
      (net 1 "GND") (pinfunction "A") (pintype "passive"))
  )
	(footprint "antmicro-footprints:C_1206_3216Metric" (layer "F.Cu")
    (at 105.675 82.86 90)
    (descr "Capacitor SMD 1206")
    (tags "capacitor SMD 1206")
    (property "Author" "Antmicro")
    (property "Dielectric" "")
    (property "License" "Apache-2.0")
    (property "MPN" "3216X5R1V226M160AC")
    (property "Manufacturer" "TDK")
    (property "Sheetfile" "power.kicad_sch")
    (property "Sheetname" "Power")
    (property "Val" "22u")
    (property "Voltage" "35V")
    (property "ki_description" "SMD Multilayer Ceramic Capacitors, 22µF, 35V, X5R, 1206 [2316 Metric], 20% ")
    (property "ki_keywords" "1206, SMT, CAPACITOR, PASSIVE, CERAMIC, MLCC")
    (attr smd)
    (fp_text reference "C8" (at -0.579 2.021 90) (layer "F.SilkS")
        (effects (font (size 0.7 0.7) (thickness 0.15)) (justify left bottom))
    )
    (fp_text value "C_22u_1206_35V" (at 0 2.101 90) (layer "F.Fab")
        (effects (font (size 0.7 0.7) (thickness 0.15)) (justify left bottom))
    )
    (fp_text user "License: Apache-2.0" (at -2.625 6.501 90) (layer "F.Fab") hide
        (effects (font (size 0.7 0.7) (thickness 0.15)) (justify left bottom))
    )
    (fp_text user "${REFERENCE}" (at -2.625 4.101 90) (layer "F.Fab") hide
        (effects (font (size 0.7 0.7) (thickness 0.15)) (justify left bottom))
    )
    (fp_text user "Author: Antmicro" (at -2.625 5.301 90) (layer "F.Fab") hide
        (effects (font (size 0.7 0.7) (thickness 0.15)) (justify left bottom))
    )
    (fp_line (start 0.8 -0.899) (end -0.8 -0.899)
      (stroke (width 0.15) (type solid)) (layer "F.SilkS"))
    (fp_line (start 0.8 0.901) (end -0.8 0.901)
      (stroke (width 0.15) (type solid)) (layer "F.SilkS"))
    (fp_rect (start -2.325 -1.15) (end 2.325 1.15)
      (stroke (width 0.05) (type default)) (fill none) (layer "F.CrtYd"))
    (fp_rect (start -1.6 -0.799) (end 1.6 0.801)
      (stroke (width 0.15) (type solid)) (fill none) (layer "F.Fab"))
    (pad "1" smd roundrect (at -1.5 0.001 90) (size 1.15 1.8) (layers "F.Cu" "F.Paste" "F.Mask") (roundrect_rratio 0.25)
      (net 1 "GND") (pintype "passive"))
    (pad "2" smd roundrect (at 1.5 0.001 90) (size 1.15 1.8) (layers "F.Cu" "F.Paste" "F.Mask") (roundrect_rratio 0.25)
      (net 74 "Net-(C10-Pad2)") (pintype "passive"))
  )
	(footprint "antmicro-footprints:TP_SMD_1mm" (layer "F.Cu")
    (at 105.991001 62.319 180)
    (property "Author" "Antmicro")
    (property "License" "Apache-2.0")
    (property "MPN" "")
    (property "Manufacturer" "")
    (property "Sheetfile" "power.kicad_sch")
    (property "Sheetname" "Power")
    (property "exclude_from_bom" "")
    (property "ki_description" "Test point 1mm SMD")
    (property "ki_keywords" "TESTPOINT")
    (attr exclude_from_pos_files exclude_from_bom)
    (fp_text reference "TP1" (at 2.613001 -0.419 180) (layer "F.SilkS")
        (effects (font (size 0.7 0.7) (thickness 0.15)) (justify left bottom))
    )
    (fp_text value "TP_1mm_SMD" (at 0 1.4 180) (layer "F.Fab")
        (effects (font (size 0.7 0.7) (thickness 0.15)) (justify left bottom))
    )
    (fp_text user "Author: Antmicro" (at -0.5 4 180) (layer "F.Fab") hide
        (effects (font (size 0.7 0.7) (thickness 0.15)) (justify left bottom))
    )
    (fp_text user "${REFERENCE}" (at -0.5 2.8 180) (layer "F.Fab") hide
        (effects (font (size 0.7 0.7) (thickness 0.15)) (justify left bottom))
    )
    (fp_text user "License: Apache-2.0" (at -0.5 5.2 180) (layer "F.Fab") hide
        (effects (font (size 0.7 0.7) (thickness 0.15)) (justify left bottom))
    )
    (fp_circle (center 0 0) (end 0.6 0)
      (stroke (width 0.05) (type default)) (fill none) (layer "F.CrtYd"))
    (pad "1" smd circle (at 0 0 180) (size 1 1) (layers "F.Cu" "F.Mask")
      (net 3 "5V0_USB") (pinfunction "1") (pintype "passive"))
  )
	(footprint "antmicro-footprints:FB_0805_2012Metric" (layer "F.Cu")
    (at 121.230001 59.1125)
    (descr "FERRITE BEAD 0805")
    (tags "FERRITE BEAD 0805")
    (property "Author" "Antmicro")
    (property "Current" "")
    (property "License" "Apache-2.0")
    (property "MPN" "BLM21SN300SZ1D")
    (property "Manufacturer" "Murata")
    (property "Sheetfile" "power.kicad_sch")
    (property "Sheetname" "Power")
    (property "Val" "30Z/8.5A")
    (property "ki_description" "Ferrite Bead, 0805 [2012 Metric], 30 ohm, 8.5 A, BLM21SN, 0.004 ohm, ± 10ohm, DC power line")
    (property "ki_keywords" "0805, SMT, FERRITE BEAD, PASSIVE")
    (attr smd)
    (fp_text reference "FB3" (at -0.834001 -0.9465) (layer "F.SilkS")
        (effects (font (size 0.7 0.7) (thickness 0.15)) (justify left bottom))
    )
    (fp_text value "FB_30Z_8.5A_Murata-BLM21SN_0805" (at 0.001 1.801) (layer "F.Fab")
        (effects (font (size 0.7 0.7) (thickness 0.15)) (justify left bottom))
    )
    (fp_text user "${REFERENCE}" (at -1.44 3.801) (layer "F.Fab") hide
        (effects (font (size 0.7 0.7) (thickness 0.15)) (justify left bottom))
    )
    (fp_text user "Author: Antmicro" (at -1.44 5.001) (layer "F.Fab") hide
        (effects (font (size 0.7 0.7) (thickness 0.15)) (justify left bottom))
    )
    (fp_text user "License: Apache-2.0" (at -1.44 6.201) (layer "F.Fab") hide
        (effects (font (size 0.7 0.7) (thickness 0.15)) (justify left bottom))
    )
    (fp_line (start -0.319 0.698) (end 0.281 0.698)
      (stroke (width 0.15) (type solid)) (layer "F.SilkS"))
    (fp_line (start -0.299 -0.698) (end 0.299 -0.698)
      (stroke (width 0.15) (type solid)) (layer "F.SilkS"))
    (fp_rect (start 1.95 -0.9) (end -1.95 0.9)
      (stroke (width 0.05) (type default)) (fill none) (layer "F.CrtYd"))
    (fp_line (start -0.948 -0.681) (end 0.948 -0.681)
      (stroke (width 0.15) (type solid)) (layer "F.Fab"))
    (fp_line (start -0.948 -0.676) (end -0.948 0.676)
      (stroke (width 0.15) (type solid)) (layer "F.Fab"))
    (fp_line (start -0.948 0.681) (end 0.948 0.681)
      (stroke (width 0.15) (type solid)) (layer "F.Fab"))
    (fp_line (start 0.948 -0.676) (end 0.948 0.676)
      (stroke (width 0.15) (type solid)) (layer "F.Fab"))
    (pad "1" smd roundrect (at -1.1 0) (size 1.2 1.3) (layers "F.Cu" "F.Paste" "F.Mask") (roundrect_rratio 0.25)
      (net 100 "Net-(D2-A)") (pintype "passive"))
    (pad "2" smd roundrect (at 1.1 0) (size 1.2 1.3) (layers "F.Cu" "F.Paste" "F.Mask") (roundrect_rratio 0.25)
      (net 2 "3V3_SYS") (pintype "passive"))
  )
	(footprint "antmicro-footprints:Fiducial_1mm_Mask3mm" (layer "F.Cu")
    (at 102 91)
    (descr "Circular Fiducial, 1.5mm bare copper, 3mm soldermask opening")
    (tags "fiducial")
    (property "Author" "Antmicro")
    (property "License" "Apache-2.0")
    (property "Sheetfile" "thunderbolt-pcie-adapter.kicad_sch")
    (property "Sheetname" "")
    (property "exclude_from_bom" "")
    (property "ki_description" "Fiducial mask")
    (attr through_hole exclude_from_bom)
    (fp_text reference "FID1" (at -1.797 2.472) (layer "F.SilkS")
        (effects (font (size 0.7 0.7) (thickness 0.15)) (justify left bottom))
    )
    (fp_text value "Fiducial_1mm_Mask3mm" (at 0 2.603) (layer "F.Fab")
        (effects (font (size 0.7 0.7) (thickness 0.15)) (justify left bottom))
    )
    (fp_text user "Author: Antmicro" (at -1.25 5.803) (layer "F.Fab") hide
        (effects (font (size 0.7 0.7) (thickness 0.15)) (justify left bottom))
    )
    (fp_text user "License: Apache-2.0" (at -1.25 7.003) (layer "F.Fab") hide
        (effects (font (size 0.7 0.7) (thickness 0.15)) (justify left bottom))
    )
    (fp_text user "${REFERENCE}" (at -1.25 4.603) (layer "F.Fab") hide
        (effects (font (size 0.7 0.7) (thickness 0.15)) (justify left bottom))
    )
    (fp_circle (center 0 0) (end 1.5 0)
      (stroke (width 0.05) (type solid)) (fill none) (layer "F.CrtYd"))
    (fp_circle (center 0 0) (end 1.5 0)
      (stroke (width 0.15) (type solid)) (fill none) (layer "F.Fab"))
    (pad "" smd circle (at 0 0) (size 1 1) (layers "F.Cu" "F.Mask")
      (solder_mask_margin 1) (clearance 1))
  )
	(footprint "antmicro-footprints:TP_SMD_1mm" (layer "F.Cu")
    (at 107.1 86.4)
    (property "Author" "Antmicro")
    (property "License" "Apache-2.0")
    (property "MPN" "")
    (property "Manufacturer" "")
    (property "Sheetfile" "power.kicad_sch")
    (property "Sheetname" "Power")
    (property "exclude_from_bom" "")
    (property "ki_description" "Test point 1mm SMD")
    (property "ki_keywords" "TESTPOINT")
    (attr exclude_from_pos_files exclude_from_bom)
    (fp_text reference "TP12" (at -6.643 -0.294) (layer "F.SilkS")
        (effects (font (size 0.7 0.7) (thickness 0.15)) (justify left bottom))
    )
    (fp_text value "TP_1mm_SMD" (at 0 1.4) (layer "F.Fab")
        (effects (font (size 0.7 0.7) (thickness 0.15)) (justify left bottom))
    )
    (fp_text user "${REFERENCE}" (at -0.5 2.8) (layer "F.Fab") hide
        (effects (font (size 0.7 0.7) (thickness 0.15)) (justify left bottom))
    )
    (fp_text user "License: Apache-2.0" (at -0.5 5.2) (layer "F.Fab") hide
        (effects (font (size 0.7 0.7) (thickness 0.15)) (justify left bottom))
    )
    (fp_text user "Author: Antmicro" (at -0.5 4) (layer "F.Fab") hide
        (effects (font (size 0.7 0.7) (thickness 0.15)) (justify left bottom))
    )
    (fp_circle (center 0 0) (end 0.6 0)
      (stroke (width 0.05) (type default)) (fill none) (layer "F.CrtYd"))
    (pad "1" smd circle (at 0 0) (size 1 1) (layers "F.Cu" "F.Mask")
      (net 61 "12V0_MOLEX") (pinfunction "1") (pintype "passive"))
  )
)
